# S9S_MB_2U (Grand Teton) — schematic netlist excerpt (pin names and nets, part order shuffled) for the footprints in the layout excerpt that follows; sources: Cadence DE-HDL packaged netlist, KiCad conversion of 03242023_DA0F0TMBIJ0_F0T_Motherboard_J_brd_V01_OCP.brd

J10  SCONN288_ADR50017P087CC  SCONN288_ADR50017-P087CC IO  pkg DDR288S_1-1VXB  page 91
  VIN_BULK0  = P12V_S3_AUX_CPU0_NVDIMM
  RFU0  = TP_CHE_CPU0_DIMM2_FRU_0
  VIN_MGMT  = P3V3_AUX
  HSCL  = I3C_SPD_DDREFGH_CPU0_LVC1_SCL_1
  HSDA  = I3C_SPD_DDREFGH_CPU0_LVC1_SDA
  VSS0  = GND
  DQ0_A  = M_E_CPU0_SA_DQ<0>
  VSS1  = GND
  DQ1_A  = M_E_CPU0_SA_DQ<1>
  VSS2  = GND
  DQS0_A_T  = M_E_CPU0_SA_DQS_DP<0>
  DQS0_A_C  = M_E_CPU0_SA_DQS_DN<0>
  VSS3  = GND
  DQ4_A  = M_E_CPU0_SA_DQ<4>
  VSS4  = GND
  DQ5_A  = M_E_CPU0_SA_DQ<5>
  VSS5  = GND
  DQ8_A  = M_E_CPU0_SA_DQ<8>
  VSS6  = GND
  DQ9_A  = M_E_CPU0_SA_DQ<9>
  VSS7  = GND
  DQS1_A_T  = M_E_CPU0_SA_DQS_DP<1>
  DQS1_A_C  = M_E_CPU0_SA_DQS_DN<1>
  VSS8  = GND
  DQ12_A  = M_E_CPU0_SA_DQ<12>
  VSS9  = GND
  DQ13_A  = M_E_CPU0_SA_DQ<13>
  VSS10  = GND
  DQ16_A  = M_E_CPU0_SA_DQ<16>
  VSS11  = GND
  DQ17_A  = M_E_CPU0_SA_DQ<17>
  VSS12  = GND
  DQS2_A_T  = M_E_CPU0_SA_DQS_DP<2>
  DQS2_A_C  = M_E_CPU0_SA_DQS_DN<2>
  VSS13  = GND
  DQ20_A  = M_E_CPU0_SA_DQ<20>
  VSS14  = GND
  DQ21_A  = M_E_CPU0_SA_DQ<21>
  VSS15  = GND
  DQ24_A  = M_E_CPU0_SA_DQ<24>
  VSS16  = GND
  DQ25_A  = M_E_CPU0_SA_DQ<25>
  VSS17  = GND
  DQS3_A_T  = M_E_CPU0_SA_DQS_DP<3>
  DQS3_A_C  = M_E_CPU0_SA_DQS_DN<3>
  VSS18  = GND
  DQ28_A  = M_E_CPU0_SA_DQ<28>
  VSS19  = GND
  DQ29_A  = M_E_CPU0_SA_DQ<29>
  VSS20  = GND
  CB0_A  = M_E_CPU0_SA_CB<0>
  VSS21  = GND
  CB1_A  = M_E_CPU0_SA_CB<1>
  VSS22  = GND
  DQS4_A_T  = M_E_CPU0_SA_DQS_DP<4>
  DQS4_A_C  = M_E_CPU0_SA_DQS_DN<4>
  VSS23  = GND
  CB4_A  = M_E_CPU0_SA_CB<4>
  VSS24  = GND
  CB5_A  = M_E_CPU0_SA_CB<5>
  VSS25  = GND
  ALERT_N  = M_E_CPU0_ALERT_N
  VSS26  = GND
  CS0_A_N  = M_E_CPU0_SA_CS_N<2>
  VSS27  = GND
  CA0_A  = M_E_CPU0_SA_CA<0>
  VSS28  = GND
  CA2_A  = M_E_CPU0_SA_CA<2>
  VSS29  = GND
  CA4_A  = M_E_CPU0_SA_CA<4>
  VSS30  = GND
  CA6_A  = M_E_CPU0_SA_CA<6>
  VSS31  = GND
  PAR_A  = M_E_CPU0_SA_PAR
  VSS32  = GND
  CA0_B  = M_E_CPU0_SB_CA<0>
  VSS33  = GND
  CA2_B  = M_E_CPU0_SB_CA<2>
  VSS34  = GND
  CA4_B  = M_E_CPU0_SB_CA<4>
  VSS35  = GND
  CA6_B  = M_E_CPU0_SB_CA<6>
  VSS36  = GND
  CS0_B_N  = M_E_CPU0_SB_CS_N<2>
  VSS37  = GND
  \lbd||rsp_a_n\  = M_E_CPU0_SA_RSP<1>
  \lbs||rsp_b_n\  = M_E_CPU0_SB_RSP<1>
  VSS38  = GND
  CB4_B  = M_E_CPU0_SB_CB<4>
  VSS39  = GND
  CB5_B  = M_E_CPU0_SB_CB<5>
  VSS40  = GND
  \dqs9_b_t||tdqs9_b_t||dbi4_b_n\  = M_E_CPU0_SB_DQS_DP<9>
  \dqs9_b_c||tdqs9_b_c\  = M_E_CPU0_SB_DQS_DN<9>
  VSS41  = GND
  CB0_B  = M_E_CPU0_SB_CB<0>
  VSS42  = GND
  CB1_B  = M_E_CPU0_SB_CB<1>
  VSS43  = GND
  DQ0_B  = M_E_CPU0_SB_DQ<0>
  VSS44  = GND
  DQ1_B  = M_E_CPU0_SB_DQ<1>
  VSS45  = GND
  DQS0_B_T  = M_E_CPU0_SB_DQS_DP<0>
  DQS0_B_C  = M_E_CPU0_SB_DQS_DN<0>
  VSS46  = GND
  DQ4_B  = M_E_CPU0_SB_DQ<4>
  VSS47  = GND
  DQ5_B  = M_E_CPU0_SB_DQ<5>
  VSS48  = GND
  DQ8_B  = M_E_CPU0_SB_DQ<8>
  VSS49  = GND
  DQ9_B  = M_E_CPU0_SB_DQ<9>
  VSS50  = GND
  DQS1_B_T  = M_E_CPU0_SB_DQS_DP<1>
  DQS1_B_C  = M_E_CPU0_SB_DQS_DN<1>
  VSS51  = GND
  DQ12_B  = M_E_CPU0_SB_DQ<12>
  VSS52  = GND
  DQ13_B  = M_E_CPU0_SB_DQ<13>
  VSS53  = GND
  DQ16_B  = M_E_CPU0_SB_DQ<16>
  VSS54  = GND
  DQ17_B  = M_E_CPU0_SB_DQ<17>
  VSS55  = GND
  DQS2_B_T  = M_E_CPU0_SB_DQS_DP<2>
  DQS2_B_C  = M_E_CPU0_SB_DQS_DN<2>
  VSS56  = GND
  DQ20_B  = M_E_CPU0_SB_DQ<20>
  VSS57  = GND
  DQ21_B  = M_E_CPU0_SB_DQ<21>
  VSS58  = GND
  DQ24_B  = M_E_CPU0_SB_DQ<24>
  VSS59  = GND
  DQ25_B  = M_E_CPU0_SB_DQ<25>
  VSS60  = GND
  DQS3_B_T  = M_E_CPU0_SB_DQS_DP<3>
  DQS3_B_C  = M_E_CPU0_SB_DQS_DN<3>
  VSS61  = GND
  DQ28_B  = M_E_CPU0_SB_DQ<28>
  VSS62  = GND
  DQ29_B  = M_E_CPU0_SB_DQ<29>
  VSS63  = GND
  RFU1  = TP_CHE_CPU0_DIMM2_FRU_1
  VIN_BULK1  = P12V_S3_AUX_CPU0_NVDIMM
  VIN_BULK2  = P12V_S3_AUX_CPU0_NVDIMM
  \pwr_good||fail_n\  = PWRGD_CHE_CPU0_DIMM2
  HSA  = PD_CHE_CPU0_DIMM2_SAA
  RFU2  = TP_CHE_CPU0_DIMM2_FRU_2
  RFU3  = TP_CHE_CPU0_DIMM2_FRU_3
  VSS64  = GND
  DQ2_A  = M_E_CPU0_SA_DQ<2>
  VSS65  = GND
  DQ3_A  = M_E_CPU0_SA_DQ<3>
  VSS66  = GND
  \dqs5_a_c||tdqs5_a_c||dqs5_a_t||tdqs5_a_t\  = M_E_CPU0_SA_DQS_DN<5>
  \dqs5_a_t||tdqs5_a_t\  = M_E_CPU0_SA_DQS_DP<5>
  VSS67  = GND
  DQ6_A  = M_E_CPU0_SA_DQ<6>
  VSS68  = GND
  DQ7_A  = M_E_CPU0_SA_DQ<7>
  VSS69  = GND
  DQ10_A  = M_E_CPU0_SA_DQ<10>
  VSS70  = GND
  DQ11_A  = M_E_CPU0_SA_DQ<11>
  VSS71  = GND
  \dqs6_a_c||tdqs6_a_c||dqs6_a_t||tdqs6_a_t\  = M_E_CPU0_SA_DQS_DN<6>
  \dqs6_a_t||tdqs6_a_t\  = M_E_CPU0_SA_DQS_DP<6>
  VSS72  = GND
  DQ14_A  = M_E_CPU0_SA_DQ<14>
  VSS73  = GND
  DQ15_A  = M_E_CPU0_SA_DQ<15>
  VSS74  = GND
  DQ18_A  = M_E_CPU0_SA_DQ<18>
  VSS75  = GND
  DQ19_A  = M_E_CPU0_SA_DQ<19>
  VSS76  = GND
  \dqs7_a_c||tdqs7_a_c\  = M_E_CPU0_SA_DQS_DN<7>
  \dqs7_a_t||tdqs7_a_t\  = M_E_CPU0_SA_DQS_DP<7>
  VSS77  = GND
  DQ22_A  = M_E_CPU0_SA_DQ<22>
  VSS78  = GND
  DQ23_A  = M_E_CPU0_SA_DQ<23>
  VSS79  = GND
  DQ26_A  = M_E_CPU0_SA_DQ<26>
  VSS80  = GND
  DQ27_A  = M_E_CPU0_SA_DQ<27>
  VSS81  = GND
  \dqs8_a_c||tdqs8_a_c\  = M_E_CPU0_SA_DQS_DN<8>
  \dqs8_a_t||tdqs8_a_t\  = M_E_CPU0_SA_DQS_DP<8>
  VSS82  = GND
  DQ30_A  = M_E_CPU0_SA_DQ<30>
  VSS83  = GND
  DQ31_A  = M_E_CPU0_SA_DQ<31>
  VSS84  = GND
  CB2_A  = M_E_CPU0_SA_CB<2>
  VSS85  = GND
  CB3_A  = M_E_CPU0_SA_CB<3>
  VSS86  = GND
  \dqs9_a_c||tdqs9_a_c\  = M_E_CPU0_SA_DQS_DN<9>
  \dqs9_a_t||tdqs9_a_t\  = M_E_CPU0_SA_DQS_DP<9>
  VSS87  = GND
  CB6_A  = M_E_CPU0_SA_CB<6>
  VSS88  = GND
  CB7_A  = M_E_CPU0_SA_CB<7>
  VSS89  = GND
  RESET_N  = RST_M_EF_CPU0_FPGA_N
  VSS90  = GND
  CS1_A_N  = M_E_CPU0_SA_CS_N<3>
  VSS91  = GND
  CA1_A  = M_E_CPU0_SA_CA<1>
  VSS92  = GND
  CA3_A  = M_E_CPU0_SA_CA<3>
  VSS93  = GND
  CA5_A  = M_E_CPU0_SA_CA<5>
  VSS94  = GND
  CK_T  = M_E_CPU0_CLK_DP<1>
  CK_C  = M_E_CPU0_CLK_DN<1>
  VSS95  = GND
  RFU4  = TP_CHE_CPU0_DIMM2_FRU_4
  CA1_B  = M_E_CPU0_SB_CA<1>
  VSS96  = GND
  CA3_B  = M_E_CPU0_SB_CA<3>
  VSS97  = GND
  CA5_B  = M_E_CPU0_SB_CA<5>
  VSS98  = GND
  PAR_B  = M_E_CPU0_SB_PAR
  VSS99  = GND
  CS1_B_N  = M_E_CPU0_SB_CS_N<3>
  VSS100  = GND
  RFU5  = TP_CHE_CPU0_DIMM2_FRU_5
  RFU6  = TP_CHE_CPU0_DIMM2_FRU_6
  VSS101  = GND
  CB6_B  = M_E_CPU0_SB_CB<6>
  VSS102  = GND
  CB7_B  = M_E_CPU0_SB_CB<7>
  VSS103  = GND
  DQS4_B_C  = M_E_CPU0_SB_DQS_DN<4>
  DQS4_B_T  = M_E_CPU0_SB_DQS_DP<4>
  VSS104  = GND
  CB2_B  = M_E_CPU0_SB_CB<2>
  VSS105  = GND
  CB3_B  = M_E_CPU0_SB_CB<3>
  VSS106  = GND
  DQ2_B  = M_E_CPU0_SB_DQ<2>
  VSS107  = GND
  DQ3_B  = M_E_CPU0_SB_DQ<3>
  VSS108  = GND
  \dqs5_b_c||tdqs5_b_c\  = M_E_CPU0_SB_DQS_DN<5>
  \dqs5_b_t||tdqs5_b_t\  = M_E_CPU0_SB_DQS_DP<5>
  VSS109  = GND
  DQ6_B  = M_E_CPU0_SB_DQ<6>
  VSS110  = GND
  DQ7_B  = M_E_CPU0_SB_DQ<7>
  VSS111  = GND
  DQ10_B  = M_E_CPU0_SB_DQ<10>
  VSS112  = GND
  DQ11_B  = M_E_CPU0_SB_DQ<11>
  VSS113  = GND
  \dqs6_b_c||tdqs6_b_c\  = M_E_CPU0_SB_DQS_DN<6>
  \dqs6_b_t||tdqs6_b_t\  = M_E_CPU0_SB_DQS_DP<6>
  VSS114  = GND
  DQ14_B  = M_E_CPU0_SB_DQ<14>
  VSS115  = GND
  DQ15_B  = M_E_CPU0_SB_DQ<15>
  VSS116  = GND
  DQ18_B  = M_E_CPU0_SB_DQ<18>
  VSS117  = GND
  DQ19_B  = M_E_CPU0_SB_DQ<19>
  VSS118  = GND
  \dqs7_b_c||tdqs7_b_c\  = M_E_CPU0_SB_DQS_DN<7>
  \dqs7_b_t||tdqs7_b_t\  = M_E_CPU0_SB_DQS_DP<7>
  VSS119  = GND
  DQ22_B  = M_E_CPU0_SB_DQ<22>
  VSS120  = GND
  DQ23_B  = M_E_CPU0_SB_DQ<23>
  VSS121  = GND
  DQ26_B  = M_E_CPU0_SB_DQ<26>
  VSS122  = GND
  DQ27_B  = M_E_CPU0_SB_DQ<27>
  VSS123  = GND
  \dqs8_b_c||tdqs8_b_c\  = M_E_CPU0_SB_DQS_DN<8>
  \dqs8_b_t||tdqs8_b_t\  = M_E_CPU0_SB_DQS_DP<8>
  VSS124  = GND
  DQ30_B  = M_E_CPU0_SB_DQ<30>
  VSS125  = GND
  DQ31_B  = M_E_CPU0_SB_DQ<31>
  VSS126  = GND
  G1  = GND
  G2  = GND
  G3  = GND

(kicad_pcb
	(version 20260206)
	(generator "pcbnew")
	(generator_version "10.0")
	(general
		(thickness 1.6)
		(legacy_teardrops no)
	)
	(paper "A4")
	(title_block
		(title "03242023_DA0F0TMBIJ0_F0T_Motherboard_J_brd_V01_OCP.brd")
		(comment 1 "Grand Teton / footprint 1607 of 6105 (J10), pads 92-137 of 291")
	)
	(layers
		(0 "F.Cu" signal "TOP")
		(4 "In1.Cu" signal "GND")
		(6 "In2.Cu" signal "IN1")
		(8 "In3.Cu" signal "GND1")
		(10 "In4.Cu" signal "IN2")
		(12 "In5.Cu" signal "GND2")
		(14 "In6.Cu" signal "IN3")
		(16 "In7.Cu" signal "GND3")
		(18 "In8.Cu" signal "VCC")
		(20 "In9.Cu" signal "VCC1")
		(22 "In10.Cu" signal "GND4")
		(24 "In11.Cu" signal "IN4")
		(26 "In12.Cu" signal "GND5")
		(28 "In13.Cu" signal "IN5")
		(30 "In14.Cu" signal "GND6")
		(32 "In15.Cu" signal "IN6")
		(34 "In16.Cu" signal "GND7")
		(2 "B.Cu" signal "BOTTOM")
		(9 "F.Adhes" user "F.Adhesive")
		(11 "B.Adhes" user "B.Adhesive")
		(13 "F.Paste" user "Package Geometry/Pastemask Top")
		(15 "B.Paste" user "Package Geometry/Pastemask Bottom")
		(5 "F.SilkS" user "Ref Des/Silkscreen Top")
		(7 "B.SilkS" user "Ref Des/Silkscreen Bottom")
		(1 "F.Mask" user "Board Geometry/Soldermask Top")
		(3 "B.Mask" user "Board Geometry/Soldermask Bottom")
		(17 "Dwgs.User" user "User.Drawings")
		(19 "Cmts.User" user "User.Comments")
		(21 "Eco1.User" user "User.Eco1")
		(23 "Eco2.User" user "User.Eco2")
		(25 "Edge.Cuts" user "Board Geometry/Outline")
		(27 "Margin" user)
		(31 "F.CrtYd" user "Package Geometry/Place Bound Top")
		(29 "B.CrtYd" user "Package Geometry/Place Bound Bottom")
		(35 "F.Fab" user "Ref Des/Assembly Top")
		(33 "B.Fab" user "Ref Des/Assembly Bottom")
	)
	(footprint ""
		(layer "F.Cu")
		(at 408.803348 -258.091686)
		(property "Reference" "J10"
			(at -3.683 -81.702148 0)
			(unlocked yes)
			(layer "F.SilkS")
			(effects
				(font
					(size 0.7874 0.5842)
					(thickness 0.1524)
				)
				(justify left)
			)
		)
		(property "Value" ""
			(at 0 0 0)
			(layer "F.Fab")
			(effects
				(font
					(size 1.27 1.27)
				)
			)
		)
		(duplicate_pad_numbers_are_jumpers no)
		(pad "92" smd rect
			(at -2.050034 19.12493 270)
			(size 0.519938 1.4986)
			(layers "F.Cu" "F.Mask" "F.Paste")
			(net "GND")
		)
		(pad "93" smd rect
			(at -2.050034 19.975068 270)
			(size 0.519938 1.4986)
			(layers "F.Cu" "F.Mask" "F.Paste")
			(net "M_E_CPU0_SB_DQS_DP<9>")
		)
		(pad "94" smd rect
			(at -2.050034 20.824952 270)
			(size 0.519938 1.4986)
			(layers "F.Cu" "F.Mask" "F.Paste")
			(net "M_E_CPU0_SB_DQS_DN<9>")
		)
		(pad "95" smd rect
			(at -2.050034 21.67509 270)
			(size 0.519938 1.4986)
			(layers "F.Cu" "F.Mask" "F.Paste")
			(net "GND")
		)
		(pad "96" smd rect
			(at -2.050034 22.524974 270)
			(size 0.519938 1.4986)
			(layers "F.Cu" "F.Mask" "F.Paste")
			(net "M_E_CPU0_SB_CB<0>")
		)
		(pad "97" smd rect
			(at -2.050034 23.375112 270)
			(size 0.519938 1.4986)
			(layers "F.Cu" "F.Mask" "F.Paste")
			(net "GND")
		)
		(pad "98" smd rect
			(at -2.050034 24.224996 270)
			(size 0.519938 1.4986)
			(layers "F.Cu" "F.Mask" "F.Paste")
			(net "M_E_CPU0_SB_CB<1>")
		)
		(pad "99" smd rect
			(at -2.050034 25.07488 270)
			(size 0.519938 1.4986)
			(layers "F.Cu" "F.Mask" "F.Paste")
			(net "GND")
		)
		(pad "100" smd rect
			(at -2.050034 25.925018 270)
			(size 0.519938 1.4986)
			(layers "F.Cu" "F.Mask" "F.Paste")
			(net "M_E_CPU0_SB_DQ<0>")
		)
		(pad "101" smd rect
			(at -2.050034 26.774902 270)
			(size 0.519938 1.4986)
			(layers "F.Cu" "F.Mask" "F.Paste")
			(net "GND")
		)
		(pad "102" smd rect
			(at -2.050034 27.62504 270)
			(size 0.519938 1.4986)
			(layers "F.Cu" "F.Mask" "F.Paste")
			(net "M_E_CPU0_SB_DQ<1>")
		)
		(pad "103" smd rect
			(at -2.050034 28.474924 270)
			(size 0.519938 1.4986)
			(layers "F.Cu" "F.Mask" "F.Paste")
			(net "GND")
		)
		(pad "104" smd rect
			(at -2.050034 29.325062 270)
			(size 0.519938 1.4986)
			(layers "F.Cu" "F.Mask" "F.Paste")
			(net "M_E_CPU0_SB_DQS_DP<0>")
		)
		(pad "105" smd rect
			(at -2.050034 30.174946 270)
			(size 0.519938 1.4986)
			(layers "F.Cu" "F.Mask" "F.Paste")
			(net "M_E_CPU0_SB_DQS_DN<0>")
		)
		(pad "106" smd rect
			(at -2.050034 31.025084 270)
			(size 0.519938 1.4986)
			(layers "F.Cu" "F.Mask" "F.Paste")
			(net "GND")
		)
		(pad "107" smd rect
			(at -2.050034 31.874968 270)
			(size 0.519938 1.4986)
			(layers "F.Cu" "F.Mask" "F.Paste")
			(net "M_E_CPU0_SB_DQ<4>")
		)
		(pad "108" smd rect
			(at -2.050034 32.725106 270)
			(size 0.519938 1.4986)
			(layers "F.Cu" "F.Mask" "F.Paste")
			(net "GND")
		)
		(pad "109" smd rect
			(at -2.050034 33.57499 270)
			(size 0.519938 1.4986)
			(layers "F.Cu" "F.Mask" "F.Paste")
			(net "M_E_CPU0_SB_DQ<5>")
		)
		(pad "110" smd rect
			(at -2.050034 34.425128 270)
			(size 0.519938 1.4986)
			(layers "F.Cu" "F.Mask" "F.Paste")
			(net "GND")
		)
		(pad "111" smd rect
			(at -2.050034 35.275012 270)
			(size 0.519938 1.4986)
			(layers "F.Cu" "F.Mask" "F.Paste")
			(net "M_E_CPU0_SB_DQ<8>")
		)
		(pad "112" smd rect
			(at -2.050034 36.124896 270)
			(size 0.519938 1.4986)
			(layers "F.Cu" "F.Mask" "F.Paste")
			(net "GND")
		)
		(pad "113" smd rect
			(at -2.050034 36.975034 270)
			(size 0.519938 1.4986)
			(layers "F.Cu" "F.Mask" "F.Paste")
			(net "M_E_CPU0_SB_DQ<9>")
		)
		(pad "114" smd rect
			(at -2.050034 37.824918 270)
			(size 0.519938 1.4986)
			(layers "F.Cu" "F.Mask" "F.Paste")
			(net "GND")
		)
		(pad "115" smd rect
			(at -2.050034 38.675056 270)
			(size 0.519938 1.4986)
			(layers "F.Cu" "F.Mask" "F.Paste")
			(net "M_E_CPU0_SB_DQS_DP<1>")
		)
		(pad "116" smd rect
			(at -2.050034 39.52494 270)
			(size 0.519938 1.4986)
			(layers "F.Cu" "F.Mask" "F.Paste")
			(net "M_E_CPU0_SB_DQS_DN<1>")
		)
		(pad "117" smd rect
			(at -2.050034 40.375078 270)
			(size 0.519938 1.4986)
			(layers "F.Cu" "F.Mask" "F.Paste")
			(net "GND")
		)
		(pad "118" smd rect
			(at -2.050034 41.224962 270)
			(size 0.519938 1.4986)
			(layers "F.Cu" "F.Mask" "F.Paste")
			(net "M_E_CPU0_SB_DQ<12>")
		)
		(pad "119" smd rect
			(at -2.050034 42.0751 270)
			(size 0.519938 1.4986)
			(layers "F.Cu" "F.Mask" "F.Paste")
			(net "GND")
		)
		(pad "120" smd rect
			(at -2.050034 42.924984 270)
			(size 0.519938 1.4986)
			(layers "F.Cu" "F.Mask" "F.Paste")
			(net "M_E_CPU0_SB_DQ<13>")
		)
		(pad "121" smd rect
			(at -2.050034 43.775122 270)
			(size 0.519938 1.4986)
			(layers "F.Cu" "F.Mask" "F.Paste")
			(net "GND")
		)
		(pad "122" smd rect
			(at -2.050034 44.625006 270)
			(size 0.519938 1.4986)
			(layers "F.Cu" "F.Mask" "F.Paste")
			(net "M_E_CPU0_SB_DQ<16>")
		)
		(pad "123" smd rect
			(at -2.050034 45.47489 270)
			(size 0.519938 1.4986)
			(layers "F.Cu" "F.Mask" "F.Paste")
			(net "GND")
		)
		(pad "124" smd rect
			(at -2.050034 46.325028 270)
			(size 0.519938 1.4986)
			(layers "F.Cu" "F.Mask" "F.Paste")
			(net "M_E_CPU0_SB_DQ<17>")
		)
		(pad "125" smd rect
			(at -2.050034 47.174912 270)
			(size 0.519938 1.4986)
			(layers "F.Cu" "F.Mask" "F.Paste")
			(net "GND")
		)
		(pad "126" smd rect
			(at -2.050034 48.02505 270)
			(size 0.519938 1.4986)
			(layers "F.Cu" "F.Mask" "F.Paste")
			(net "M_E_CPU0_SB_DQS_DP<2>")
		)
		(pad "127" smd rect
			(at -2.050034 48.874934 270)
			(size 0.519938 1.4986)
			(layers "F.Cu" "F.Mask" "F.Paste")
			(net "M_E_CPU0_SB_DQS_DN<2>")
		)
		(pad "128" smd rect
			(at -2.050034 49.725072 270)
			(size 0.519938 1.4986)
			(layers "F.Cu" "F.Mask" "F.Paste")
			(net "GND")
		)
		(pad "129" smd rect
			(at -2.050034 50.574956 270)
			(size 0.519938 1.4986)
			(layers "F.Cu" "F.Mask" "F.Paste")
			(net "M_E_CPU0_SB_DQ<20>")
		)
		(pad "130" smd rect
			(at -2.050034 51.425094 270)
			(size 0.519938 1.4986)
			(layers "F.Cu" "F.Mask" "F.Paste")
			(net "GND")
		)
		(pad "131" smd rect
			(at -2.050034 52.274978 270)
			(size 0.519938 1.4986)
			(layers "F.Cu" "F.Mask" "F.Paste")
			(net "M_E_CPU0_SB_DQ<21>")
		)
		(pad "132" smd rect
			(at -2.050034 53.125116 270)
			(size 0.519938 1.4986)
			(layers "F.Cu" "F.Mask" "F.Paste")
			(net "GND")
		)
		(pad "133" smd rect
			(at -2.050034 53.975 270)
			(size 0.519938 1.4986)
			(layers "F.Cu" "F.Mask" "F.Paste")
			(net "M_E_CPU0_SB_DQ<24>")
		)
		(pad "134" smd rect
			(at -2.050034 54.824884 270)
			(size 0.519938 1.4986)
			(layers "F.Cu" "F.Mask" "F.Paste")
			(net "GND")
		)
		(pad "135" smd rect
			(at -2.050034 55.675022 270)
			(size 0.519938 1.4986)
			(layers "F.Cu" "F.Mask" "F.Paste")
			(net "M_E_CPU0_SB_DQ<25>")
		)
		(pad "136" smd rect
			(at -2.050034 56.524906 270)
			(size 0.519938 1.4986)
			(layers "F.Cu" "F.Mask" "F.Paste")
			(net "GND")
		)
		(pad "137" smd rect
			(at -2.050034 57.375044 270)
			(size 0.519938 1.4986)
			(layers "F.Cu" "F.Mask" "F.Paste")
			(net "M_E_CPU0_SB_DQS_DP<3>")
		)
	)
)
